FILE_TYPE = MULTI_PHYS_TABLE;

PART 'RS53318LR'

{========================================================================================}
:VALUE       | PART_TYPE | MATERIAL | PART_NUMBER    = STANDARD | LIFECYCLE          | PART_NUMBER   | JEDEC_TYPE  | DESCRIPTION             | MANUFTR | MANUF_PN    | RD_CMPLS_LVL | CMPLS_LVL | FROM_PJ    | CLASS | DIP_SMD | DATA                | EE_CHECK_LIST | FP_ECN | PSL | CREATOR | STATUS | MSD | ESD_CDM | ESD_HBM | ESD_MM | PIN_LENGTH_SHORT_PIN | PIN_LENGTH_LONG_PIN | CREATEDAY  ;
{========================================================================================}
 'RS53318LR' | 'SMLF'    | 'IC'     | 'AL053318002'(!) = ''       | ''               | 'AL053318002' |'QFN21_4X3'| 'IC(21P)RS53318LR(QFN)' | 'RDS'   | 'RS53318LR' | 'EP(V1)'     | 'EP(V1)'  | 'F0T-GREG' | 'IC'  | ''      | 'RDS_RS53318LR.pdf' | ''            | ''     | ''  | ''      | ''     | ''  | ''      | ''      | ''     | '0 MILS'             | '0 MILS'            | '20220510'
 'RS53318LR' | 'SMLF'    | 'EMPTY'  | 'AL053318002'(!) = ''       | ''               | 'AL053318002' |'QFN21_4X3'| 'IC(21P)RS53318LR(QFN)' | 'RDS'   | 'RS53318LR' | 'EP(V1)'     | 'EP(V1)'  | 'F0T-GREG' | 'IC'  | ''      | 'RDS_RS53318LR.pdf' | ''            | ''     | ''  | ''      | ''     | ''  | ''      | ''      | ''     | '0 MILS'             | '0 MILS'            | '20220510'

END_PART

END.

